(kicad_pcb
	(version 20260206)
	(generator "pcbnew")
	(generator_version "10.0")
	(general
		(thickness 1.6)
		(legacy_teardrops no)
	)
	(paper "A4")
	(title_block
		(title "peb — Lightning_PEB_BRD.brd")
		(comment 1 "Lightning (Wiwynn / Facebook NVMe JBOF) / footprints 2521-2528 of 2563")
	)
	(layers
		(0 "F.Cu" signal "TOP")
		(4 "In1.Cu" signal "L2GND")
		(6 "In2.Cu" signal "L3")
		(8 "In3.Cu" signal "L4VCC")
		(10 "In4.Cu" signal "L5VCC")
		(12 "In5.Cu" signal "L6")
		(14 "In6.Cu" signal "L7GND")
		(2 "B.Cu" signal "BOTTOM")
		(9 "F.Adhes" user "F.Adhesive")
		(11 "B.Adhes" user "B.Adhesive")
		(13 "F.Paste" user "Package Geometry/Pastemask Top")
		(15 "B.Paste" user "Package Geometry/Pastemask Bottom")
		(5 "F.SilkS" user "Ref Des/Silkscreen Top")
		(7 "B.SilkS" user "Ref Des/Silkscreen Bottom")
		(1 "F.Mask" user "Board Geometry/Soldermask Top")
		(3 "B.Mask" user "Board Geometry/Soldermask Bottom")
		(17 "Dwgs.User" user "User.Drawings")
		(19 "Cmts.User" user "User.Comments")
		(21 "Eco1.User" user "User.Eco1")
		(23 "Eco2.User" user "User.Eco2")
		(25 "Edge.Cuts" user "Board Geometry/Outline")
		(27 "Margin" user)
		(31 "F.CrtYd" user "Package Geometry/Place Bound Top")
		(29 "B.CrtYd" user "Package Geometry/Place Bound Bottom")
		(35 "F.Fab" user "Ref Des/Assembly Top")
		(33 "B.Fab" user "Ref Des/Assembly Bottom")
	)
	(footprint ""
		(layer "B.Cu")
		(at 51.5366 -127.7112 90)
		(property "Reference" "R469"
			(at 0 0 90)
			(layer "B.SilkS")
			(hide yes)
			(effects
				(font
					(size 1.27 1.27)
				)
				(justify mirror)
			)
		)
		(property "Value" "0R2J-2-GP"
			(at -0.064008 -3.993896 90)
			(unlocked yes)
			(layer "B.Fab")
			(hide yes)
			(effects
				(font
					(size 1.016 1.016)
					(thickness 0.1524)
				)
				(justify mirror)
			)
		)
		(property "Device Type" "R402H16"
			(at -0.064008 -5.517896 90)
			(unlocked yes)
			(layer "B.Fab")
			(hide yes)
			(effects
				(font
					(size 1.016 1.016)
					(thickness 0.1524)
				)
				(justify mirror)
			)
		)
		(duplicate_pad_numbers_are_jumpers no)
		(fp_line
			(start 0.508 -0.9398)
			(end 0.508 0.9398)
			(stroke
				(width 0.1524)
				(type default)
			)
			(layer "B.SilkS")
		)
		(fp_line
			(start -0.508 -0.9398)
			(end 0.508 -0.9398)
			(stroke
				(width 0.1524)
				(type default)
			)
			(layer "B.SilkS")
		)
		(fp_rect
			(start 0.508 0.9398)
			(end -0.508 -0.9398)
			(stroke
				(width 0)
				(type default)
			)
			(fill no)
			(layer "B.CrtYd")
		)
		(fp_rect
			(start 0.508 0.9398)
			(end -0.508 -0.9398)
			(stroke
				(width 0)
				(type default)
			)
			(fill no)
			(layer "B.Fab")
		)
		(pad "1" smd custom
			(at 0 -0.4445 270)
			(size 0.1397 0.1397)
			(layers "B.Cu" "B.Mask" "B.Paste")
			(net "BMC0_SMB14_SDA")
			(options
				(clearance outline)
				(anchor circle)
			)
			(primitives
				(gr_poly
					(pts
						(arc
							(start -0.1778 0.2794)
							(mid -0.249642 0.249642)
							(end -0.2794 0.1778)
						)
						(arc
							(start -0.2794 -0.1778)
							(mid -0.249642 -0.249642)
							(end -0.1778 -0.2794)
						)
						(arc
							(start 0.1778 -0.2794)
							(mid 0.249642 -0.249642)
							(end 0.2794 -0.1778)
						)
						(arc
							(start 0.2794 0.1778)
							(mid 0.249642 0.249642)
							(end 0.1778 0.2794)
						)
					)
					(width 0)
					(fill yes)
				)
			)
		)
		(pad "2" smd custom
			(at 0 0.4445 270)
			(size 0.1397 0.1397)
			(layers "B.Cu" "B.Mask" "B.Paste")
			(net "BMC_I2C14_MINI8_SDA_S")
			(options
				(clearance outline)
				(anchor circle)
			)
			(primitives
				(gr_poly
					(pts
						(arc
							(start -0.1778 0.2794)
							(mid -0.249642 0.249642)
							(end -0.2794 0.1778)
						)
						(arc
							(start -0.2794 -0.1778)
							(mid -0.249642 -0.249642)
							(end -0.1778 -0.2794)
						)
						(arc
							(start 0.1778 -0.2794)
							(mid 0.249642 -0.249642)
							(end 0.2794 -0.1778)
						)
						(arc
							(start 0.2794 0.1778)
							(mid 0.249642 0.249642)
							(end 0.1778 0.2794)
						)
					)
					(width 0)
					(fill yes)
				)
			)
		)
	)
	(footprint ""
		(layer "B.Cu")
		(at 237.1598 -47.032672 90)
		(property "Reference" "C39"
			(at 0 0 90)
			(layer "B.SilkS")
			(hide yes)
			(effects
				(font
					(size 1.27 1.27)
				)
				(justify mirror)
			)
		)
		(property "Value" "SCD1U16V1KX-1-GP"
			(at 2.8321 -1.7399 90)
			(unlocked yes)
			(layer "B.Fab")
			(hide yes)
			(effects
				(font
					(size 1.016 1.016)
					(thickness 0.1524)
				)
				(justify mirror)
			)
		)
		(property "Device Type" "C0201H13"
			(at 2.8321 -3.2639 90)
			(unlocked yes)
			(layer "B.Fab")
			(hide yes)
			(effects
				(font
					(size 1.016 1.016)
					(thickness 0.1524)
				)
				(justify mirror)
			)
		)
		(duplicate_pad_numbers_are_jumpers no)
		(fp_rect
			(start 0.2794 0.6477)
			(end -0.2794 -0.6477)
			(stroke
				(width 0)
				(type default)
			)
			(fill no)
			(layer "B.CrtYd")
		)
		(fp_rect
			(start 0.2794 0.6477)
			(end -0.2794 -0.6477)
			(stroke
				(width 0)
				(type default)
			)
			(fill no)
			(layer "B.Fab")
		)
		(pad "1" smd custom
			(at 0 -0.2794 270)
			(size 0.0762 0.0762)
			(layers "B.Cu" "B.Mask" "B.Paste")
			(net "DUT_VDD")
			(options
				(clearance outline)
				(anchor circle)
			)
			(primitives
				(gr_poly
					(pts
						(arc
							(start 0.1524 0.127)
							(mid 0.137521 0.162921)
							(end 0.1016 0.1778)
						)
						(arc
							(start -0.1016 0.1778)
							(mid -0.137521 0.162921)
							(end -0.1524 0.127)
						)
						(arc
							(start -0.1524 -0.127)
							(mid -0.137521 -0.162921)
							(end -0.1016 -0.1778)
						)
						(arc
							(start 0.1016 -0.1778)
							(mid 0.137521 -0.162921)
							(end 0.1524 -0.127)
						)
					)
					(width 0)
					(fill yes)
				)
			)
		)
		(pad "2" smd custom
			(at 0 0.2794 270)
			(size 0.0762 0.0762)
			(layers "B.Cu" "B.Mask" "B.Paste")
			(net "GND")
			(options
				(clearance outline)
				(anchor circle)
			)
			(primitives
				(gr_poly
					(pts
						(arc
							(start 0.1524 0.127)
							(mid 0.137521 0.162921)
							(end 0.1016 0.1778)
						)
						(arc
							(start -0.1016 0.1778)
							(mid -0.137521 0.162921)
							(end -0.1524 0.127)
						)
						(arc
							(start -0.1524 -0.127)
							(mid -0.137521 -0.162921)
							(end -0.1016 -0.1778)
						)
						(arc
							(start 0.1016 -0.1778)
							(mid 0.137521 -0.162921)
							(end 0.1524 -0.127)
						)
					)
					(width 0)
					(fill yes)
				)
			)
		)
	)
	(footprint ""
		(layer "B.Cu")
		(at 14.6558 -126.365 180)
		(property "Reference" "R522"
			(at 0 0 0)
			(layer "B.SilkS")
			(hide yes)
			(effects
				(font
					(size 1.27 1.27)
				)
				(justify mirror)
			)
		)
		(property "Value" "4K7R2F-GP"
			(at -0.064008 -3.993896 180)
			(unlocked yes)
			(layer "B.Fab")
			(hide yes)
			(effects
				(font
					(size 1.016 1.016)
					(thickness 0.1524)
				)
				(justify mirror)
			)
		)
		(property "Device Type" "R402H16"
			(at -0.064008 -5.517896 180)
			(unlocked yes)
			(layer "B.Fab")
			(hide yes)
			(effects
				(font
					(size 1.016 1.016)
					(thickness 0.1524)
				)
				(justify mirror)
			)
		)
		(duplicate_pad_numbers_are_jumpers no)
		(fp_line
			(start 0.508 -0.9398)
			(end 0.508 0.9398)
			(stroke
				(width 0.1524)
				(type default)
			)
			(layer "B.SilkS")
		)
		(fp_line
			(start -0.508 -0.9398)
			(end 0.508 -0.9398)
			(stroke
				(width 0.1524)
				(type default)
			)
			(layer "B.SilkS")
		)
		(fp_rect
			(start 0.508 0.9398)
			(end -0.508 -0.9398)
			(stroke
				(width 0)
				(type default)
			)
			(fill no)
			(layer "B.CrtYd")
		)
		(fp_rect
			(start 0.508 0.9398)
			(end -0.508 -0.9398)
			(stroke
				(width 0)
				(type default)
			)
			(fill no)
			(layer "B.Fab")
		)
		(pad "1" smd custom
			(at 0 -0.4445)
			(size 0.1397 0.1397)
			(layers "B.Cu" "B.Mask" "B.Paste")
			(net "BMC_I2C2_MINI2_SDA_S")
			(options
				(clearance outline)
				(anchor circle)
			)
			(primitives
				(gr_poly
					(pts
						(arc
							(start -0.1778 0.2794)
							(mid -0.249642 0.249642)
							(end -0.2794 0.1778)
						)
						(arc
							(start -0.2794 -0.1778)
							(mid -0.249642 -0.249642)
							(end -0.1778 -0.2794)
						)
						(arc
							(start 0.1778 -0.2794)
							(mid 0.249642 -0.249642)
							(end 0.2794 -0.1778)
						)
						(arc
							(start 0.2794 0.1778)
							(mid 0.249642 0.249642)
							(end 0.1778 0.2794)
						)
					)
					(width 0)
					(fill yes)
				)
			)
		)
		(pad "2" smd custom
			(at 0 0.4445)
			(size 0.1397 0.1397)
			(layers "B.Cu" "B.Mask" "B.Paste")
			(net "P3V3_STBY")
			(options
				(clearance outline)
				(anchor circle)
			)
			(primitives
				(gr_poly
					(pts
						(arc
							(start -0.1778 0.2794)
							(mid -0.249642 0.249642)
							(end -0.2794 0.1778)
						)
						(arc
							(start -0.2794 -0.1778)
							(mid -0.249642 -0.249642)
							(end -0.1778 -0.2794)
						)
						(arc
							(start 0.1778 -0.2794)
							(mid 0.249642 -0.249642)
							(end 0.2794 -0.1778)
						)
						(arc
							(start 0.2794 0.1778)
							(mid 0.249642 0.249642)
							(end 0.1778 0.2794)
						)
					)
					(width 0)
					(fill yes)
				)
			)
		)
	)
	(footprint ""
		(layer "B.Cu")
		(at 186.7154 -71.628 180)
		(property "Reference" "C540"
			(at 0 0 0)
			(layer "B.SilkS")
			(hide yes)
			(effects
				(font
					(size 1.27 1.27)
				)
				(justify mirror)
			)
		)
		(property "Value" "SC4D7U16V5KX-1-GP"
			(at 0.0762 -6.1214 180)
			(unlocked yes)
			(layer "B.Fab")
			(hide yes)
			(effects
				(font
					(size 1.016 1.016)
					(thickness 0.1524)
				)
				(justify mirror)
			)
		)
		(property "Device Type" "C805H56"
			(at 0.0762 -8.1534 180)
			(unlocked yes)
			(layer "B.Fab")
			(hide yes)
			(effects
				(font
					(size 1.016 1.016)
					(thickness 0.1524)
				)
				(justify mirror)
			)
		)
		(duplicate_pad_numbers_are_jumpers no)
		(fp_line
			(start -0.635 0)
			(end 0.635 0)
			(stroke
				(width 0.508)
				(type default)
			)
			(layer "B.SilkS")
		)
		(fp_rect
			(start 0.9652 1.778)
			(end -0.9652 -1.778)
			(stroke
				(width 0)
				(type default)
			)
			(fill no)
			(layer "B.CrtYd")
		)
		(fp_poly
			(pts
				(xy 0.9652 -1.778) (xy -0.9652 -1.778) (xy -0.9652 1.778) (xy 0.9652 1.778)
			)
			(stroke
				(width 0)
				(type default)
			)
			(fill no)
			(layer "B.Fab")
		)
		(pad "1" smd rect
			(at 0 -0.9652)
			(size 1.397 1.143)
			(layers "B.Cu" "B.Mask" "B.Paste")
			(net "DUT_AVD_PCIE")
		)
		(pad "2" smd rect
			(at 0 0.9652)
			(size 1.397 1.143)
			(layers "B.Cu" "B.Mask" "B.Paste")
			(net "GND")
		)
	)
	(footprint ""
		(layer "B.Cu")
		(at 242.130072 -41.012872 -90)
		(property "Reference" "C498"
			(at 0 0 90)
			(layer "B.SilkS")
			(hide yes)
			(effects
				(font
					(size 1.27 1.27)
				)
				(justify mirror)
			)
		)
		(property "Value" "SCD1U16V1KX-1-GP"
			(at 2.8321 -1.7399 270)
			(unlocked yes)
			(layer "B.Fab")
			(hide yes)
			(effects
				(font
					(size 1.016 1.016)
					(thickness 0.1524)
				)
				(justify mirror)
			)
		)
		(property "Device Type" "C0201H13"
			(at 2.8321 -3.2639 270)
			(unlocked yes)
			(layer "B.Fab")
			(hide yes)
			(effects
				(font
					(size 1.016 1.016)
					(thickness 0.1524)
				)
				(justify mirror)
			)
		)
		(duplicate_pad_numbers_are_jumpers no)
		(fp_rect
			(start 0.2794 0.6477)
			(end -0.2794 -0.6477)
			(stroke
				(width 0)
				(type default)
			)
			(fill no)
			(layer "B.CrtYd")
		)
		(fp_rect
			(start 0.2794 0.6477)
			(end -0.2794 -0.6477)
			(stroke
				(width 0)
				(type default)
			)
			(fill no)
			(layer "B.Fab")
		)
		(pad "1" smd custom
			(at 0 -0.2794 90)
			(size 0.0762 0.0762)
			(layers "B.Cu" "B.Mask" "B.Paste")
			(net "DUT_AVD_PCIE_Q")
			(options
				(clearance outline)
				(anchor circle)
			)
			(primitives
				(gr_poly
					(pts
						(arc
							(start 0.1524 0.127)
							(mid 0.137521 0.162921)
							(end 0.1016 0.1778)
						)
						(arc
							(start -0.1016 0.1778)
							(mid -0.137521 0.162921)
							(end -0.1524 0.127)
						)
						(arc
							(start -0.1524 -0.127)
							(mid -0.137521 -0.162921)
							(end -0.1016 -0.1778)
						)
						(arc
							(start 0.1016 -0.1778)
							(mid 0.137521 -0.162921)
							(end 0.1524 -0.127)
						)
					)
					(width 0)
					(fill yes)
				)
			)
		)
		(pad "2" smd custom
			(at 0 0.2794 90)
			(size 0.0762 0.0762)
			(layers "B.Cu" "B.Mask" "B.Paste")
			(net "GND")
			(options
				(clearance outline)
				(anchor circle)
			)
			(primitives
				(gr_poly
					(pts
						(arc
							(start 0.1524 0.127)
							(mid 0.137521 0.162921)
							(end 0.1016 0.1778)
						)
						(arc
							(start -0.1016 0.1778)
							(mid -0.137521 0.162921)
							(end -0.1524 0.127)
						)
						(arc
							(start -0.1524 -0.127)
							(mid -0.137521 -0.162921)
							(end -0.1016 -0.1778)
						)
						(arc
							(start 0.1016 -0.1778)
							(mid 0.137521 -0.162921)
							(end 0.1524 -0.127)
						)
					)
					(width 0)
					(fill yes)
				)
			)
		)
	)
	(footprint ""
		(layer "B.Cu")
		(at 235.1024 -47.032672 -90)
		(property "Reference" "C40"
			(at 0 0 90)
			(layer "B.SilkS")
			(hide yes)
			(effects
				(font
					(size 1.27 1.27)
				)
				(justify mirror)
			)
		)
		(property "Value" "SCD1U16V1KX-1-GP"
			(at 2.8321 -1.7399 270)
			(unlocked yes)
			(layer "B.Fab")
			(hide yes)
			(effects
				(font
					(size 1.016 1.016)
					(thickness 0.1524)
				)
				(justify mirror)
			)
		)
		(property "Device Type" "C0201H13"
			(at 2.8321 -3.2639 270)
			(unlocked yes)
			(layer "B.Fab")
			(hide yes)
			(effects
				(font
					(size 1.016 1.016)
					(thickness 0.1524)
				)
				(justify mirror)
			)
		)
		(duplicate_pad_numbers_are_jumpers no)
		(fp_rect
			(start 0.2794 0.6477)
			(end -0.2794 -0.6477)
			(stroke
				(width 0)
				(type default)
			)
			(fill no)
			(layer "B.CrtYd")
		)
		(fp_rect
			(start 0.2794 0.6477)
			(end -0.2794 -0.6477)
			(stroke
				(width 0)
				(type default)
			)
			(fill no)
			(layer "B.Fab")
		)
		(pad "1" smd custom
			(at 0 -0.2794 90)
			(size 0.0762 0.0762)
			(layers "B.Cu" "B.Mask" "B.Paste")
			(net "DUT_VDD")
			(options
				(clearance outline)
				(anchor circle)
			)
			(primitives
				(gr_poly
					(pts
						(arc
							(start 0.1524 0.127)
							(mid 0.137521 0.162921)
							(end 0.1016 0.1778)
						)
						(arc
							(start -0.1016 0.1778)
							(mid -0.137521 0.162921)
							(end -0.1524 0.127)
						)
						(arc
							(start -0.1524 -0.127)
							(mid -0.137521 -0.162921)
							(end -0.1016 -0.1778)
						)
						(arc
							(start 0.1016 -0.1778)
							(mid 0.137521 -0.162921)
							(end 0.1524 -0.127)
						)
					)
					(width 0)
					(fill yes)
				)
			)
		)
		(pad "2" smd custom
			(at 0 0.2794 90)
			(size 0.0762 0.0762)
			(layers "B.Cu" "B.Mask" "B.Paste")
			(net "GND")
			(options
				(clearance outline)
				(anchor circle)
			)
			(primitives
				(gr_poly
					(pts
						(arc
							(start 0.1524 0.127)
							(mid 0.137521 0.162921)
							(end 0.1016 0.1778)
						)
						(arc
							(start -0.1016 0.1778)
							(mid -0.137521 0.162921)
							(end -0.1524 0.127)
						)
						(arc
							(start -0.1524 -0.127)
							(mid -0.137521 -0.162921)
							(end -0.1016 -0.1778)
						)
						(arc
							(start 0.1016 -0.1778)
							(mid 0.137521 -0.162921)
							(end 0.1524 -0.127)
						)
					)
					(width 0)
					(fill yes)
				)
			)
		)
	)
	(footprint ""
		(layer "B.Cu")
		(at 150.460202 -56.542432)
		(property "Reference" "PR169"
			(at 0 0 0)
			(layer "B.SilkS")
			(hide yes)
			(effects
				(font
					(size 1.27 1.27)
				)
				(justify mirror)
			)
		)
		(property "Value" "187KR2F-GP"
			(at -0.064008 -3.993896 0)
			(unlocked yes)
			(layer "B.Fab")
			(hide yes)
			(effects
				(font
					(size 1.016 1.016)
					(thickness 0.1524)
				)
				(justify mirror)
			)
		)
		(property "Device Type" "R402H16"
			(at -0.064008 -5.517896 0)
			(unlocked yes)
			(layer "B.Fab")
			(hide yes)
			(effects
				(font
					(size 1.016 1.016)
					(thickness 0.1524)
				)
				(justify mirror)
			)
		)
		(duplicate_pad_numbers_are_jumpers no)
		(fp_line
			(start -0.508 -0.9398)
			(end 0.508 -0.9398)
			(stroke
				(width 0.1524)
				(type default)
			)
			(layer "B.SilkS")
		)
		(fp_line
			(start 0.508 -0.9398)
			(end 0.508 0.9398)
			(stroke
				(width 0.1524)
				(type default)
			)
			(layer "B.SilkS")
		)
		(fp_rect
			(start 0.508 0.9398)
			(end -0.508 -0.9398)
			(stroke
				(width 0)
				(type default)
			)
			(fill no)
			(layer "B.CrtYd")
		)
		(fp_rect
			(start 0.508 0.9398)
			(end -0.508 -0.9398)
			(stroke
				(width 0)
				(type default)
			)
			(fill no)
			(layer "B.Fab")
		)
		(pad "1" smd custom
			(at 0 -0.4445 180)
			(size 0.1397 0.1397)
			(layers "B.Cu" "B.Mask" "B.Paste")
			(net "P0V9_RF")
			(options
				(clearance outline)
				(anchor circle)
			)
			(primitives
				(gr_poly
					(pts
						(arc
							(start -0.1778 0.2794)
							(mid -0.249642 0.249642)
							(end -0.2794 0.1778)
						)
						(arc
							(start -0.2794 -0.1778)
							(mid -0.249642 -0.249642)
							(end -0.1778 -0.2794)
						)
						(arc
							(start 0.1778 -0.2794)
							(mid 0.249642 -0.249642)
							(end 0.2794 -0.1778)
						)
						(arc
							(start 0.2794 0.1778)
							(mid 0.249642 0.249642)
							(end 0.1778 0.2794)
						)
					)
					(width 0)
					(fill yes)
				)
			)
		)
		(pad "2" smd custom
			(at 0 0.4445 180)
			(size 0.1397 0.1397)
			(layers "B.Cu" "B.Mask" "B.Paste")
			(net "AGND_P0V9")
			(options
				(clearance outline)
				(anchor circle)
			)
			(primitives
				(gr_poly
					(pts
						(arc
							(start -0.1778 0.2794)
							(mid -0.249642 0.249642)
							(end -0.2794 0.1778)
						)
						(arc
							(start -0.2794 -0.1778)
							(mid -0.249642 -0.249642)
							(end -0.1778 -0.2794)
						)
						(arc
							(start 0.1778 -0.2794)
							(mid 0.249642 -0.249642)
							(end 0.2794 -0.1778)
						)
						(arc
							(start 0.2794 0.1778)
							(mid 0.249642 0.249642)
							(end 0.1778 0.2794)
						)
					)
					(width 0)
					(fill yes)
				)
			)
		)
	)
	(footprint ""
		(layer "B.Cu")
		(at 349.640906 -42.98569 90)
		(property "Reference" "R7906"
			(at 0 0 90)
			(layer "B.SilkS")
			(hide yes)
			(effects
				(font
					(size 1.27 1.27)
				)
				(justify mirror)
			)
		)
		(property "Value" "0R2J-2-GP"
			(at -0.064008 -3.993896 90)
			(unlocked yes)
			(layer "B.Fab")
			(hide yes)
			(effects
				(font
					(size 1.016 1.016)
					(thickness 0.1524)
				)
				(justify mirror)
			)
		)
		(property "Device Type" "R402H16"
			(at -0.064008 -5.517896 90)
			(unlocked yes)
			(layer "B.Fab")
			(hide yes)
			(effects
				(font
					(size 1.016 1.016)
					(thickness 0.1524)
				)
				(justify mirror)
			)
		)
		(duplicate_pad_numbers_are_jumpers no)
		(fp_line
			(start 0.508 -0.9398)
			(end 0.508 0.9398)
			(stroke
				(width 0.1524)
				(type default)
			)
			(layer "B.SilkS")
		)
		(fp_line
			(start -0.508 -0.9398)
			(end 0.508 -0.9398)
			(stroke
				(width 0.1524)
				(type default)
			)
			(layer "B.SilkS")
		)
		(fp_rect
			(start 0.508 0.9398)
			(end -0.508 -0.9398)
			(stroke
				(width 0)
				(type default)
			)
			(fill no)
			(layer "B.CrtYd")
		)
		(fp_rect
			(start 0.508 0.9398)
			(end -0.508 -0.9398)
			(stroke
				(width 0)
				(type default)
			)
			(fill no)
			(layer "B.Fab")
		)
		(pad "1" smd custom
			(at 0 -0.4445 270)
			(size 0.1397 0.1397)
			(layers "B.Cu" "B.Mask" "B.Paste")
			(net "SLIDE_SW_PMC_RST#")
			(options
				(clearance outline)
				(anchor circle)
			)
			(primitives
				(gr_poly
					(pts
						(arc
							(start -0.1778 0.2794)
							(mid -0.249642 0.249642)
							(end -0.2794 0.1778)
						)
						(arc
							(start -0.2794 -0.1778)
							(mid -0.249642 -0.249642)
							(end -0.1778 -0.2794)
						)
						(arc
							(start 0.1778 -0.2794)
							(mid 0.249642 -0.249642)
							(end 0.2794 -0.1778)
						)
						(arc
							(start 0.2794 0.1778)
							(mid 0.249642 0.249642)
							(end 0.1778 0.2794)
						)
					)
					(width 0)
					(fill yes)
				)
			)
		)
		(pad "2" smd custom
			(at 0 0.4445 270)
			(size 0.1397 0.1397)
			(layers "B.Cu" "B.Mask" "B.Paste")
			(net "PM8536_PG2_R")
			(options
				(clearance outline)
				(anchor circle)
			)
			(primitives
				(gr_poly
					(pts
						(arc
							(start -0.1778 0.2794)
							(mid -0.249642 0.249642)
							(end -0.2794 0.1778)
						)
						(arc
							(start -0.2794 -0.1778)
							(mid -0.249642 -0.249642)
							(end -0.1778 -0.2794)
						)
						(arc
							(start 0.1778 -0.2794)
							(mid 0.249642 -0.249642)
							(end 0.2794 -0.1778)
						)
						(arc
							(start 0.2794 0.1778)
							(mid 0.249642 0.249642)
							(end 0.1778 0.2794)
						)
					)
					(width 0)
					(fill yes)
				)
			)
		)
	)
)
